(kicad_pcb
	(version 20260206)
	(generator "pcbnew")
	(generator_version "10.0")
	(general
		(thickness 1.6)
		(legacy_teardrops no)
	)
	(paper "A4")
	(title_block
		(title "peb — Lightning_PEB_BRD.brd")
		(comment 1 "Lightning (Wiwynn / Facebook NVMe JBOF) / footprints 2224-2230 of 2563")
	)
	(layers
		(0 "F.Cu" signal "TOP")
		(4 "In1.Cu" signal "L2GND")
		(6 "In2.Cu" signal "L3")
		(8 "In3.Cu" signal "L4VCC")
		(10 "In4.Cu" signal "L5VCC")
		(12 "In5.Cu" signal "L6")
		(14 "In6.Cu" signal "L7GND")
		(2 "B.Cu" signal "BOTTOM")
		(9 "F.Adhes" user "F.Adhesive")
		(11 "B.Adhes" user "B.Adhesive")
		(13 "F.Paste" user "Package Geometry/Pastemask Top")
		(15 "B.Paste" user "Package Geometry/Pastemask Bottom")
		(5 "F.SilkS" user "Ref Des/Silkscreen Top")
		(7 "B.SilkS" user "Ref Des/Silkscreen Bottom")
		(1 "F.Mask" user "Board Geometry/Soldermask Top")
		(3 "B.Mask" user "Board Geometry/Soldermask Bottom")
		(17 "Dwgs.User" user "User.Drawings")
		(19 "Cmts.User" user "User.Comments")
		(21 "Eco1.User" user "User.Eco1")
		(23 "Eco2.User" user "User.Eco2")
		(25 "Edge.Cuts" user "Board Geometry/Outline")
		(27 "Margin" user)
		(31 "F.CrtYd" user "Package Geometry/Place Bound Top")
		(29 "B.CrtYd" user "Package Geometry/Place Bound Bottom")
		(35 "F.Fab" user "Ref Des/Assembly Top")
		(33 "B.Fab" user "Ref Des/Assembly Bottom")
	)
	(footprint ""
		(layer "B.Cu")
		(at 224.409 -10.287 180)
		(property "Reference" "PQ22"
			(at 0 0 0)
			(layer "B.SilkS")
			(hide yes)
			(effects
				(font
					(size 1.27 1.27)
				)
				(justify mirror)
			)
		)
		(property "Value" "AO3400-GP-U"
			(at -0.0254 -12.3444 180)
			(unlocked yes)
			(layer "B.Fab")
			(hide yes)
			(effects
				(font
					(size 1.016 1.016)
					(thickness 0.1524)
				)
				(justify mirror)
			)
		)
		(property "Device Type" "SOT23DGS2D8H50"
			(at -0.0254 -14.2494 180)
			(unlocked yes)
			(layer "B.Fab")
			(hide yes)
			(effects
				(font
					(size 1.016 1.016)
					(thickness 0.1524)
				)
				(justify mirror)
			)
		)
		(duplicate_pad_numbers_are_jumpers no)
		(fp_line
			(start 1.7018 0.254)
			(end 1.7018 -0.254)
			(stroke
				(width 0.1524)
				(type default)
			)
			(layer "B.SilkS")
		)
		(fp_line
			(start 1.7018 -0.254)
			(end -1.7018 -0.254)
			(stroke
				(width 0.1524)
				(type default)
			)
			(layer "B.SilkS")
		)
		(fp_line
			(start -1.7018 0.254)
			(end 1.7018 0.254)
			(stroke
				(width 0.1524)
				(type default)
			)
			(layer "B.SilkS")
		)
		(fp_line
			(start -1.7018 -0.254)
			(end -1.7018 0.254)
			(stroke
				(width 0.1524)
				(type default)
			)
			(layer "B.SilkS")
		)
		(fp_rect
			(start 1.778 1.9812)
			(end -1.778 -1.9812)
			(stroke
				(width 0)
				(type default)
			)
			(fill no)
			(layer "B.CrtYd")
		)
		(fp_poly
			(pts
				(xy 1.778 -1.9812) (xy -1.778 -1.9812) (xy -1.778 1.9812) (xy 1.778 1.9812)
			)
			(stroke
				(width 0)
				(type default)
			)
			(fill no)
			(layer "B.Fab")
		)
		(pad "D" smd custom
			(at 0 -1.1176)
			(size 0.254 0.254)
			(layers "B.Cu" "B.Mask" "B.Paste")
			(net "U81_B")
			(options
				(clearance outline)
				(anchor circle)
			)
			(primitives
				(gr_poly
					(pts
						(arc
							(start -0.508 0.4064)
							(mid -0.448484 0.550084)
							(end -0.3048 0.6096)
						)
						(arc
							(start 0.3048 0.6096)
							(mid 0.448484 0.550084)
							(end 0.508 0.4064)
						)
						(arc
							(start 0.508 -0.4064)
							(mid 0.448484 -0.550084)
							(end 0.3048 -0.6096)
						)
						(arc
							(start -0.3048 -0.6096)
							(mid -0.448484 -0.550084)
							(end -0.508 -0.4064)
						)
					)
					(width 0)
					(fill yes)
				)
			)
		)
		(pad "G" smd custom
			(at 1.016 1.1176)
			(size 0.254 0.254)
			(layers "B.Cu" "B.Mask" "B.Paste")
			(net "PQ22_G")
			(options
				(clearance outline)
				(anchor circle)
			)
			(primitives
				(gr_poly
					(pts
						(arc
							(start -0.508 0.4064)
							(mid -0.448484 0.550084)
							(end -0.3048 0.6096)
						)
						(arc
							(start 0.3048 0.6096)
							(mid 0.448484 0.550084)
							(end 0.508 0.4064)
						)
						(arc
							(start 0.508 -0.4064)
							(mid 0.448484 -0.550084)
							(end 0.3048 -0.6096)
						)
						(arc
							(start -0.3048 -0.6096)
							(mid -0.448484 -0.550084)
							(end -0.508 -0.4064)
						)
					)
					(width 0)
					(fill yes)
				)
			)
		)
		(pad "S" smd custom
			(at -1.016 1.1176)
			(size 0.254 0.254)
			(layers "B.Cu" "B.Mask" "B.Paste")
			(net "GND")
			(options
				(clearance outline)
				(anchor circle)
			)
			(primitives
				(gr_poly
					(pts
						(arc
							(start -0.508 0.4064)
							(mid -0.448484 0.550084)
							(end -0.3048 0.6096)
						)
						(arc
							(start 0.3048 0.6096)
							(mid 0.448484 0.550084)
							(end 0.508 0.4064)
						)
						(arc
							(start 0.508 -0.4064)
							(mid 0.448484 -0.550084)
							(end 0.3048 -0.6096)
						)
						(arc
							(start -0.3048 -0.6096)
							(mid -0.448484 -0.550084)
							(end -0.508 -0.4064)
						)
					)
					(width 0)
					(fill yes)
				)
			)
		)
	)
	(footprint ""
		(layer "B.Cu")
		(at 338.868512 -184.878218 180)
		(property "Reference" "R4152"
			(at 0 0 0)
			(layer "B.SilkS")
			(hide yes)
			(effects
				(font
					(size 1.27 1.27)
				)
				(justify mirror)
			)
		)
		(property "Value" "4K7R2F-GP"
			(at -0.064008 -3.993896 180)
			(unlocked yes)
			(layer "B.Fab")
			(hide yes)
			(effects
				(font
					(size 1.016 1.016)
					(thickness 0.1524)
				)
				(justify mirror)
			)
		)
		(property "Device Type" "R402H16"
			(at -0.064008 -5.517896 180)
			(unlocked yes)
			(layer "B.Fab")
			(hide yes)
			(effects
				(font
					(size 1.016 1.016)
					(thickness 0.1524)
				)
				(justify mirror)
			)
		)
		(duplicate_pad_numbers_are_jumpers no)
		(fp_line
			(start 0.508 -0.9398)
			(end 0.508 0.9398)
			(stroke
				(width 0.1524)
				(type default)
			)
			(layer "B.SilkS")
		)
		(fp_line
			(start -0.508 -0.9398)
			(end 0.508 -0.9398)
			(stroke
				(width 0.1524)
				(type default)
			)
			(layer "B.SilkS")
		)
		(fp_rect
			(start 0.508 0.9398)
			(end -0.508 -0.9398)
			(stroke
				(width 0)
				(type default)
			)
			(fill no)
			(layer "B.CrtYd")
		)
		(fp_rect
			(start 0.508 0.9398)
			(end -0.508 -0.9398)
			(stroke
				(width 0)
				(type default)
			)
			(fill no)
			(layer "B.Fab")
		)
		(pad "1" smd custom
			(at 0 -0.4445)
			(size 0.1397 0.1397)
			(layers "B.Cu" "B.Mask" "B.Paste")
			(net "SSD_ATNLED#14")
			(options
				(clearance outline)
				(anchor circle)
			)
			(primitives
				(gr_poly
					(pts
						(arc
							(start -0.1778 0.2794)
							(mid -0.249642 0.249642)
							(end -0.2794 0.1778)
						)
						(arc
							(start -0.2794 -0.1778)
							(mid -0.249642 -0.249642)
							(end -0.1778 -0.2794)
						)
						(arc
							(start 0.1778 -0.2794)
							(mid 0.249642 -0.249642)
							(end 0.2794 -0.1778)
						)
						(arc
							(start 0.2794 0.1778)
							(mid 0.249642 0.249642)
							(end 0.1778 0.2794)
						)
					)
					(width 0)
					(fill yes)
				)
			)
		)
		(pad "2" smd custom
			(at 0 0.4445)
			(size 0.1397 0.1397)
			(layers "B.Cu" "B.Mask" "B.Paste")
			(net "P3V3_STBY")
			(options
				(clearance outline)
				(anchor circle)
			)
			(primitives
				(gr_poly
					(pts
						(arc
							(start -0.1778 0.2794)
							(mid -0.249642 0.249642)
							(end -0.2794 0.1778)
						)
						(arc
							(start -0.2794 -0.1778)
							(mid -0.249642 -0.249642)
							(end -0.1778 -0.2794)
						)
						(arc
							(start 0.1778 -0.2794)
							(mid 0.249642 -0.249642)
							(end 0.2794 -0.1778)
						)
						(arc
							(start 0.2794 0.1778)
							(mid 0.249642 0.249642)
							(end 0.1778 0.2794)
						)
					)
					(width 0)
					(fill yes)
				)
			)
		)
	)
	(footprint ""
		(layer "B.Cu")
		(at 40.005 -117.602)
		(property "Reference" "TP327"
			(at 0 0 0)
			(layer "B.SilkS")
			(hide yes)
			(effects
				(font
					(size 1.27 1.27)
				)
				(justify mirror)
			)
		)
		(property "Value" "TPAD28-2-GP"
			(at 0.0127 -1.6637 0)
			(unlocked yes)
			(layer "B.Fab")
			(hide yes)
			(effects
				(font
					(size 1.016 1.016)
					(thickness 0.1524)
				)
				(justify mirror)
			)
		)
		(property "Device Type" "TPAD28"
			(at 0.0127 -3.1877 0)
			(unlocked yes)
			(layer "B.Fab")
			(hide yes)
			(effects
				(font
					(size 1.016 1.016)
					(thickness 0.1524)
				)
				(justify mirror)
			)
		)
		(duplicate_pad_numbers_are_jumpers no)
		(fp_poly
			(pts
				(arc
					(start 0.3556 0)
					(mid -0.3556 0)
					(end 0.3556 0)
				)
			)
			(stroke
				(width 0)
				(type default)
			)
			(fill no)
			(layer "B.CrtYd")
		)
		(fp_poly
			(pts
				(arc
					(start 0.6096 0)
					(mid -0.6096 0)
					(end 0.6096 0)
				)
			)
			(stroke
				(width 0)
				(type default)
			)
			(fill no)
			(layer "B.Fab")
		)
		(pad "1" smd circle
			(at 0 0 180)
			(size 0.7112 0.7112)
			(layers "B.Cu" "B.Mask" "B.Paste")
			(net "TP_GPIOU2")
		)
	)
	(footprint ""
		(layer "B.Cu")
		(at 124.262388 -202.811126)
		(property "Reference" "U71"
			(at 0 0 0)
			(layer "B.SilkS")
			(hide yes)
			(effects
				(font
					(size 1.27 1.27)
				)
				(justify mirror)
			)
		)
		(property "Value" "SN74LVC1G08DCKR-GP"
			(at 2.3368 -8.6868 0)
			(unlocked yes)
			(layer "B.Fab")
			(hide yes)
			(effects
				(font
					(size 1.016 1.016)
					(thickness 0.1524)
				)
				(justify mirror)
			)
		)
		(property "Device Type" "SC70-5H44"
			(at 2.3114 -10.414 0)
			(unlocked yes)
			(layer "B.Fab")
			(hide yes)
			(effects
				(font
					(size 1.016 1.016)
					(thickness 0.1524)
				)
				(justify mirror)
			)
		)
		(duplicate_pad_numbers_are_jumpers no)
		(fp_line
			(start -1.3843 -1.8034)
			(end -1.3843 -1.1176)
			(stroke
				(width 0.3302)
				(type default)
			)
			(layer "B.SilkS")
		)
		(fp_line
			(start -1.27 -1.7018)
			(end -1.27 1.7018)
			(stroke
				(width 0.1524)
				(type default)
			)
			(layer "B.SilkS")
		)
		(fp_line
			(start -1.27 1.7018)
			(end 1.27 1.7018)
			(stroke
				(width 0.1524)
				(type default)
			)
			(layer "B.SilkS")
		)
		(fp_line
			(start -0.6604 -1.8034)
			(end -1.3843 -1.8034)
			(stroke
				(width 0.3302)
				(type default)
			)
			(layer "B.SilkS")
		)
		(fp_line
			(start 1.27 -1.7018)
			(end -1.27 -1.7018)
			(stroke
				(width 0.1524)
				(type default)
			)
			(layer "B.SilkS")
		)
		(fp_line
			(start 1.27 1.7018)
			(end 1.27 -1.7018)
			(stroke
				(width 0.1524)
				(type default)
			)
			(layer "B.SilkS")
		)
		(fp_rect
			(start 1.524 1.9558)
			(end -1.524 -1.9558)
			(stroke
				(width 0)
				(type default)
			)
			(fill no)
			(layer "B.CrtYd")
		)
		(fp_poly
			(pts
				(xy 1.524 -1.9558) (xy -1.524 -1.9558) (xy -1.524 1.9558) (xy 1.524 1.9558)
			)
			(stroke
				(width 0)
				(type default)
			)
			(fill no)
			(layer "B.Fab")
		)
		(pad "1" smd rect
			(at -0.65024 -0.8255 180)
			(size 0.4064 1.2192)
			(layers "B.Cu" "B.Mask" "B.Paste")
			(net "BMC_SSD_RST#0_A7")
		)
		(pad "2" smd rect
			(at 0 -0.8255 180)
			(size 0.4064 1.2192)
			(layers "B.Cu" "B.Mask" "B.Paste")
			(net "SSD_PERST#0_B7")
		)
		(pad "3" smd rect
			(at 0.65024 -0.8255 180)
			(size 0.4064 1.2192)
			(layers "B.Cu" "B.Mask" "B.Paste")
			(net "GND")
		)
		(pad "4" smd rect
			(at 0.65024 0.8255 180)
			(size 0.4064 1.2192)
			(layers "B.Cu" "B.Mask" "B.Paste")
			(net "SSD_PERST_Y7")
		)
		(pad "5" smd rect
			(at -0.65024 0.8255 180)
			(size 0.4064 1.2192)
			(layers "B.Cu" "B.Mask" "B.Paste")
			(net "P3V3_STBY")
		)
	)
	(footprint ""
		(layer "B.Cu")
		(at 243.1288 -48.9966 -90)
		(property "Reference" "C447"
			(at 0 0 90)
			(layer "B.SilkS")
			(hide yes)
			(effects
				(font
					(size 1.27 1.27)
				)
				(justify mirror)
			)
		)
		(property "Value" "SCD1U16V1KX-1-GP"
			(at 2.8321 -1.7399 270)
			(unlocked yes)
			(layer "B.Fab")
			(hide yes)
			(effects
				(font
					(size 1.016 1.016)
					(thickness 0.1524)
				)
				(justify mirror)
			)
		)
		(property "Device Type" "C0201H13"
			(at 2.8321 -3.2639 270)
			(unlocked yes)
			(layer "B.Fab")
			(hide yes)
			(effects
				(font
					(size 1.016 1.016)
					(thickness 0.1524)
				)
				(justify mirror)
			)
		)
		(duplicate_pad_numbers_are_jumpers no)
		(fp_rect
			(start 0.2794 0.6477)
			(end -0.2794 -0.6477)
			(stroke
				(width 0)
				(type default)
			)
			(fill no)
			(layer "B.CrtYd")
		)
		(fp_rect
			(start 0.2794 0.6477)
			(end -0.2794 -0.6477)
			(stroke
				(width 0)
				(type default)
			)
			(fill no)
			(layer "B.Fab")
		)
		(pad "1" smd custom
			(at 0 -0.2794 90)
			(size 0.0762 0.0762)
			(layers "B.Cu" "B.Mask" "B.Paste")
			(net "DUT_VDD")
			(options
				(clearance outline)
				(anchor circle)
			)
			(primitives
				(gr_poly
					(pts
						(arc
							(start 0.1524 0.127)
							(mid 0.137521 0.162921)
							(end 0.1016 0.1778)
						)
						(arc
							(start -0.1016 0.1778)
							(mid -0.137521 0.162921)
							(end -0.1524 0.127)
						)
						(arc
							(start -0.1524 -0.127)
							(mid -0.137521 -0.162921)
							(end -0.1016 -0.1778)
						)
						(arc
							(start 0.1016 -0.1778)
							(mid 0.137521 -0.162921)
							(end 0.1524 -0.127)
						)
					)
					(width 0)
					(fill yes)
				)
			)
		)
		(pad "2" smd custom
			(at 0 0.2794 90)
			(size 0.0762 0.0762)
			(layers "B.Cu" "B.Mask" "B.Paste")
			(net "GND")
			(options
				(clearance outline)
				(anchor circle)
			)
			(primitives
				(gr_poly
					(pts
						(arc
							(start 0.1524 0.127)
							(mid 0.137521 0.162921)
							(end 0.1016 0.1778)
						)
						(arc
							(start -0.1016 0.1778)
							(mid -0.137521 0.162921)
							(end -0.1524 0.127)
						)
						(arc
							(start -0.1524 -0.127)
							(mid -0.137521 -0.162921)
							(end -0.1016 -0.1778)
						)
						(arc
							(start 0.1016 -0.1778)
							(mid 0.137521 -0.162921)
							(end 0.1524 -0.127)
						)
					)
					(width 0)
					(fill yes)
				)
			)
		)
	)
	(footprint ""
		(layer "B.Cu")
		(at 337.241388 -178.808126)
		(property "Reference" "U73"
			(at 0 0 0)
			(layer "B.SilkS")
			(hide yes)
			(effects
				(font
					(size 1.27 1.27)
				)
				(justify mirror)
			)
		)
		(property "Value" "SN74LVC1G08DCKR-GP"
			(at 2.3368 -8.6868 0)
			(unlocked yes)
			(layer "B.Fab")
			(hide yes)
			(effects
				(font
					(size 1.016 1.016)
					(thickness 0.1524)
				)
				(justify mirror)
			)
		)
		(property "Device Type" "SC70-5H44"
			(at 2.3114 -10.414 0)
			(unlocked yes)
			(layer "B.Fab")
			(hide yes)
			(effects
				(font
					(size 1.016 1.016)
					(thickness 0.1524)
				)
				(justify mirror)
			)
		)
		(duplicate_pad_numbers_are_jumpers no)
		(fp_line
			(start -1.3843 -1.8034)
			(end -1.3843 -1.1176)
			(stroke
				(width 0.3302)
				(type default)
			)
			(layer "B.SilkS")
		)
		(fp_line
			(start -1.27 -1.7018)
			(end -1.27 1.7018)
			(stroke
				(width 0.1524)
				(type default)
			)
			(layer "B.SilkS")
		)
		(fp_line
			(start -1.27 1.7018)
			(end 1.27 1.7018)
			(stroke
				(width 0.1524)
				(type default)
			)
			(layer "B.SilkS")
		)
		(fp_line
			(start -0.6604 -1.8034)
			(end -1.3843 -1.8034)
			(stroke
				(width 0.3302)
				(type default)
			)
			(layer "B.SilkS")
		)
		(fp_line
			(start 1.27 -1.7018)
			(end -1.27 -1.7018)
			(stroke
				(width 0.1524)
				(type default)
			)
			(layer "B.SilkS")
		)
		(fp_line
			(start 1.27 1.7018)
			(end 1.27 -1.7018)
			(stroke
				(width 0.1524)
				(type default)
			)
			(layer "B.SilkS")
		)
		(fp_rect
			(start 1.524 1.9558)
			(end -1.524 -1.9558)
			(stroke
				(width 0)
				(type default)
			)
			(fill no)
			(layer "B.CrtYd")
		)
		(fp_poly
			(pts
				(xy 1.524 -1.9558) (xy -1.524 -1.9558) (xy -1.524 1.9558) (xy 1.524 1.9558)
			)
			(stroke
				(width 0)
				(type default)
			)
			(fill no)
			(layer "B.Fab")
		)
		(pad "1" smd rect
			(at -0.65024 -0.8255 180)
			(size 0.4064 1.2192)
			(layers "B.Cu" "B.Mask" "B.Paste")
			(net "BMC_SSD_RST#0_A9")
		)
		(pad "2" smd rect
			(at 0 -0.8255 180)
			(size 0.4064 1.2192)
			(layers "B.Cu" "B.Mask" "B.Paste")
			(net "SSD_PERST#0_B9")
		)
		(pad "3" smd rect
			(at 0.65024 -0.8255 180)
			(size 0.4064 1.2192)
			(layers "B.Cu" "B.Mask" "B.Paste")
			(net "GND")
		)
		(pad "4" smd rect
			(at 0.65024 0.8255 180)
			(size 0.4064 1.2192)
			(layers "B.Cu" "B.Mask" "B.Paste")
			(net "SSD_PERST_Y9")
		)
		(pad "5" smd rect
			(at -0.65024 0.8255 180)
			(size 0.4064 1.2192)
			(layers "B.Cu" "B.Mask" "B.Paste")
			(net "P3V3_STBY")
		)
	)
	(footprint ""
		(layer "B.Cu")
		(at 58.166 -132.08 180)
		(property "Reference" "R5768"
			(at 0 0 0)
			(layer "B.SilkS")
			(hide yes)
			(effects
				(font
					(size 1.27 1.27)
				)
				(justify mirror)
			)
		)
		(property "Value" "1KR2F-3-GP"
			(at -0.064008 -3.993896 180)
			(unlocked yes)
			(layer "B.Fab")
			(hide yes)
			(effects
				(font
					(size 1.016 1.016)
					(thickness 0.1524)
				)
				(justify mirror)
			)
		)
		(property "Device Type" "R402H16"
			(at -0.064008 -5.517896 180)
			(unlocked yes)
			(layer "B.Fab")
			(hide yes)
			(effects
				(font
					(size 1.016 1.016)
					(thickness 0.1524)
				)
				(justify mirror)
			)
		)
		(duplicate_pad_numbers_are_jumpers no)
		(fp_line
			(start 0.508 -0.9398)
			(end 0.508 0.9398)
			(stroke
				(width 0.1524)
				(type default)
			)
			(layer "B.SilkS")
		)
		(fp_line
			(start -0.508 -0.9398)
			(end 0.508 -0.9398)
			(stroke
				(width 0.1524)
				(type default)
			)
			(layer "B.SilkS")
		)
		(fp_rect
			(start 0.508 0.9398)
			(end -0.508 -0.9398)
			(stroke
				(width 0)
				(type default)
			)
			(fill no)
			(layer "B.CrtYd")
		)
		(fp_rect
			(start 0.508 0.9398)
			(end -0.508 -0.9398)
			(stroke
				(width 0)
				(type default)
			)
			(fill no)
			(layer "B.Fab")
		)
		(pad "1" smd custom
			(at 0 -0.4445)
			(size 0.1397 0.1397)
			(layers "B.Cu" "B.Mask" "B.Paste")
			(net "P3V3_STBY")
			(options
				(clearance outline)
				(anchor circle)
			)
			(primitives
				(gr_poly
					(pts
						(arc
							(start -0.1778 0.2794)
							(mid -0.249642 0.249642)
							(end -0.2794 0.1778)
						)
						(arc
							(start -0.2794 -0.1778)
							(mid -0.249642 -0.249642)
							(end -0.1778 -0.2794)
						)
						(arc
							(start 0.1778 -0.2794)
							(mid 0.249642 -0.249642)
							(end 0.2794 -0.1778)
						)
						(arc
							(start 0.2794 0.1778)
							(mid 0.249642 0.249642)
							(end 0.1778 0.2794)
						)
					)
					(width 0)
					(fill yes)
				)
			)
		)
		(pad "2" smd custom
			(at 0 0.4445)
			(size 0.1397 0.1397)
			(layers "B.Cu" "B.Mask" "B.Paste")
			(net "ADC_P3V3_STBY")
			(options
				(clearance outline)
				(anchor circle)
			)
			(primitives
				(gr_poly
					(pts
						(arc
							(start -0.1778 0.2794)
							(mid -0.249642 0.249642)
							(end -0.2794 0.1778)
						)
						(arc
							(start -0.2794 -0.1778)
							(mid -0.249642 -0.249642)
							(end -0.1778 -0.2794)
						)
						(arc
							(start 0.1778 -0.2794)
							(mid 0.249642 -0.249642)
							(end 0.2794 -0.1778)
						)
						(arc
							(start 0.2794 0.1778)
							(mid 0.249642 0.249642)
							(end 0.1778 0.2794)
						)
					)
					(width 0)
					(fill yes)
				)
			)
		)
	)
)
